FILE_TYPE = CONNECTIVITY;
{Allegro Design Entry HDL 17.2-2016 S081 (4005846) 1/11/2022}
"PAGE_NUMBER" = 117;
0"NC";
1"PVNN_TERM_CPU0\g";
2"PVNN_TERM_CPU1\g";
3"GND\g";
4"GND\g";
5"H_PMAX_TRIGGER_IO_CPU1"CDS_PHYS_NET_NAME"H_PMAX_TRIGGER_IO_CPU1";
6"H_PMAX_TRIGGER_IO_CPU0"CDS_PHYS_NET_NAME"H_PMAX_TRIGGER_IO_CPU1";
7"H_CPU_PM_FAST_WAKE_N"CDS_PHYS_NET_NAME"H_PMAX_TRIGGER_IO_CPU1";
8"H_CPU1_PM_FAST_WAKE_N"CDS_PHYS_NET_NAME"H_PMAX_TRIGGER_IO_CPU1";
9"H_CPU0_PM_FAST_WAKE_N"CDS_PHYS_NET_NAME"H_PMAX_TRIGGER_IO_CPU1";
%"Q_RES"
"1","(-700,3350)","0","pure_quanta","I10";
;
PART_NUMBER"CS00002JB13"
MATERIAL"CHIP"
WATTAGE"1/16W"
VALUE"0"
TOLERANCE"5%"
PACK_TYPE"0402LF"
$LOCATION"R3023"
CDS_LIB"pure_quanta"
CDS_LOCATION"R3023"
$SEC"1"
CDS_SEC"1";
"B"
$PN"2"8;
"A"
$PN"1"7;
%"Q_RES"
"2","(-1875,3650)","0","pure_quanta","I13";
;
PART_NUMBER"CS13012FB02"
MATERIAL"CHIP"
PACK_TYPE"0402LF"
TOLERANCE"1%"
WATTAGE"1/16W"
VALUE"301"
$LOCATION"R1242"
CDS_LIB"pure_quanta"
CDS_LOCATION"R1242"
$SEC"1"
CDS_SEC"1";
"A"
$PN"1"1;
"B"
$PN"2"7;
%"UNIVERSAL_POWER"
"1","(-1875,3925)","0","logical_power","I14";
;
HDL_POWER"PVNN_TERM_CPU0"
CDS_LIB"logical_power";
"A"1;
%"UNIVERSAL_POWER"
"1","(-1075,3925)","0","logical_power","I15";
;
HDL_POWER"PVNN_TERM_CPU1"
CDS_LIB"logical_power";
"A"2;
%"Q_RES"
"2","(-1075,3650)","0","pure_quanta","I16";
;
PART_NUMBER"CS13012FB02"
VALUE"301"
MATERIAL"CHIP"
WATTAGE"1/16W"
PACK_TYPE"0402LF"
TOLERANCE"1%"
$LOCATION"R1244"
CDS_LIB"pure_quanta"
CDS_LOCATION"R1244"
$SEC"1"
CDS_SEC"1";
"A"
$PN"1"2;
"B"
$PN"2"7;
%"Q_RES"
"2","(-3100,5100)","0","pure_quanta","I17";
;
PART_NUMBER"CS12492FB02"
MATERIAL"CHIP"
PACK_TYPE"0402LF"
VALUE"249"
WATTAGE"1/16W"
TOLERANCE"1%"
$LOCATION"R1241"
CDS_LIB"pure_quanta"
CDS_LOCATION"R1241"
$SEC"1"
CDS_SEC"1";
"A"
$PN"1"6;
"B"
$PN"2"3;
%"UNIVERSAL_GND"
"1","(-3100,4850)","0","logical_power","I18";
;
CDS_LIB"logical_power"
HDL_POWER"GND";
"A"3;
%"Q_RES"
"2","(-2825,5100)","0","pure_quanta","I19";
;
PART_NUMBER"CS12492FB02"
WATTAGE"1/16W"
TOLERANCE"1%"
MATERIAL"CHIP"
VALUE"249"
PACK_TYPE"0402LF"
$LOCATION"R1243"
CDS_LIB"pure_quanta"
CDS_LOCATION"R1243"
$SEC"1"
CDS_SEC"1";
"A"
$PN"1"5;
"B"
$PN"2"4;
%"UNIVERSAL_GND"
"1","(-2825,4850)","0","logical_power","I20";
;
CDS_LIB"logical_power"
HDL_POWER"GND";
"A"4;
%"Q_RES"
"1","(-2175,3350)","0","pure_quanta","I9";
;
PART_NUMBER"CS00002JB13"
PACK_TYPE"0402LF"
TOLERANCE"5%"
VALUE"0"
WATTAGE"1/16W"
MATERIAL"CHIP"
$LOCATION"R1240"
CDS_LIB"pure_quanta"
CDS_LOCATION"R1240"
$SEC"1"
CDS_SEC"1";
"B"
$PN"2"7;
"A"
$PN"1"9;
END.
